(kicad_pcb
	(version 20260206)
	(generator "pcbnew")
	(generator_version "10.0")
	(general
		(thickness 1.6)
		(legacy_teardrops no)
	)
	(paper "A4")
	(title_block
		(title "01162023_DA0F0TEBIF0_F0T_Expander_BD_F_brd_V02_OCP.brd")
		(comment 1 "Grand Teton / footprints 4786-4792 of 9728")
	)
	(layers
		(0 "F.Cu" signal "TOP")
		(4 "In1.Cu" signal "GND")
		(6 "In2.Cu" signal "VCC")
		(8 "In3.Cu" signal "VCC1")
		(10 "In4.Cu" signal "GND1")
		(12 "In5.Cu" signal "IN1")
		(14 "In6.Cu" signal "GND2")
		(16 "In7.Cu" signal "IN2")
		(18 "In8.Cu" signal "GND3")
		(20 "In9.Cu" signal "IN3")
		(22 "In10.Cu" signal "GND4")
		(24 "In11.Cu" signal "IN4")
		(26 "In12.Cu" signal "GND5")
		(28 "In13.Cu" signal "IN5")
		(30 "In14.Cu" signal "GND6")
		(32 "In15.Cu" signal "IN6")
		(34 "In16.Cu" signal "GND7")
		(2 "B.Cu" signal "BOTTOM")
		(9 "F.Adhes" user "F.Adhesive")
		(11 "B.Adhes" user "B.Adhesive")
		(13 "F.Paste" user "Package Geometry/Pastemask Top")
		(15 "B.Paste" user "Package Geometry/Pastemask Bottom")
		(5 "F.SilkS" user "Ref Des/Silkscreen Top")
		(7 "B.SilkS" user "Ref Des/Silkscreen Bottom")
		(1 "F.Mask" user "Board Geometry/Soldermask Top")
		(3 "B.Mask" user "Board Geometry/Soldermask Bottom")
		(17 "Dwgs.User" user "User.Drawings")
		(19 "Cmts.User" user "User.Comments")
		(21 "Eco1.User" user "User.Eco1")
		(23 "Eco2.User" user "User.Eco2")
		(25 "Edge.Cuts" user "Board Geometry/Outline")
		(27 "Margin" user)
		(31 "F.CrtYd" user "Package Geometry/Place Bound Top")
		(29 "B.CrtYd" user "Package Geometry/Place Bound Bottom")
		(35 "F.Fab" user "Ref Des/Assembly Top")
		(33 "B.Fab" user "Ref Des/Assembly Bottom")
	)
	(footprint ""
		(layer "F.Cu")
		(at 441.273692 -356.244906 90)
		(property "Reference" "C795"
			(at 0 0 90)
			(layer "F.SilkS")
			(hide yes)
			(effects
				(font
					(size 1.27 1.27)
				)
			)
		)
		(property "Value" ""
			(at 0 0 90)
			(layer "F.Fab")
			(effects
				(font
					(size 1.27 1.27)
				)
			)
		)
		(duplicate_pad_numbers_are_jumpers no)
		(fp_line
			(start 0.299974 -0.150114)
			(end 0.299974 0.150114)
			(stroke
				(width 0.1)
				(type default)
			)
			(layer "F.Fab")
		)
		(fp_line
			(start -0.299974 -0.150114)
			(end 0.299974 -0.150114)
			(stroke
				(width 0.1)
				(type default)
			)
			(layer "F.Fab")
		)
		(fp_line
			(start 0.299974 0.150114)
			(end -0.299974 0.150114)
			(stroke
				(width 0.1)
				(type default)
			)
			(layer "F.Fab")
		)
		(fp_line
			(start -0.299974 0.150114)
			(end -0.299974 -0.150114)
			(stroke
				(width 0.1)
				(type default)
			)
			(layer "F.Fab")
		)
		(pad "1" smd rect
			(at -0.2667 0 90)
			(size 0.3048 0.381)
			(layers "F.Cu" "F.Mask" "F.Paste")
			(net "P5E_PEX3_STN7_TX_DN<127>")
		)
		(pad "2" smd rect
			(at 0.2667 0 90)
			(size 0.3048 0.381)
			(layers "F.Cu" "F.Mask" "F.Paste")
			(net "P5E_PEX3_STN7_TX_C_DN<127>")
		)
	)
	(footprint ""
		(layer "F.Cu")
		(at 56.26481 -384.973068)
		(property "Reference" "C4025"
			(at 0 0 0)
			(layer "F.SilkS")
			(hide yes)
			(effects
				(font
					(size 1.27 1.27)
				)
			)
		)
		(property "Value" ""
			(at 0 0 0)
			(layer "F.Fab")
			(effects
				(font
					(size 1.27 1.27)
				)
			)
		)
		(duplicate_pad_numbers_are_jumpers no)
		(fp_line
			(start -0.7874 -0.4064)
			(end 0.7874 -0.4064)
			(stroke
				(width 0.1524)
				(type default)
			)
			(layer "F.SilkS")
		)
		(fp_line
			(start -0.7874 0.4064)
			(end -0.7874 -0.4064)
			(stroke
				(width 0.1524)
				(type default)
			)
			(layer "F.SilkS")
		)
		(fp_line
			(start 0.7874 -0.4064)
			(end 0.7874 0.4064)
			(stroke
				(width 0.1524)
				(type default)
			)
			(layer "F.SilkS")
		)
		(fp_line
			(start 0.7874 0.4064)
			(end -0.7874 0.4064)
			(stroke
				(width 0.1524)
				(type default)
			)
			(layer "F.SilkS")
		)
		(fp_line
			(start -0.67945 -0.305054)
			(end -0.12065 -0.305054)
			(stroke
				(width 0.1)
				(type default)
			)
			(layer "F.Fab")
		)
		(fp_line
			(start -0.67945 0.3048)
			(end -0.67945 -0.305054)
			(stroke
				(width 0.1)
				(type default)
			)
			(layer "F.Fab")
		)
		(fp_line
			(start -0.12065 -0.305054)
			(end -0.12065 -0.2794)
			(stroke
				(width 0.1)
				(type default)
			)
			(layer "F.Fab")
		)
		(fp_line
			(start -0.12065 -0.2794)
			(end 0.12065 -0.2794)
			(stroke
				(width 0.1)
				(type default)
			)
			(layer "F.Fab")
		)
		(fp_line
			(start -0.12065 0.2794)
			(end -0.12065 0.3048)
			(stroke
				(width 0.1)
				(type default)
			)
			(layer "F.Fab")
		)
		(fp_line
			(start -0.12065 0.3048)
			(end -0.67945 0.3048)
			(stroke
				(width 0.1)
				(type default)
			)
			(layer "F.Fab")
		)
		(fp_line
			(start 0.120396 0.2794)
			(end -0.12065 0.2794)
			(stroke
				(width 0.1)
				(type default)
			)
			(layer "F.Fab")
		)
		(fp_line
			(start 0.120396 0.3048)
			(end 0.120396 0.2794)
			(stroke
				(width 0.1)
				(type default)
			)
			(layer "F.Fab")
		)
		(fp_line
			(start 0.12065 -0.3048)
			(end 0.67945 -0.3048)
			(stroke
				(width 0.1)
				(type default)
			)
			(layer "F.Fab")
		)
		(fp_line
			(start 0.12065 -0.2794)
			(end 0.12065 -0.3048)
			(stroke
				(width 0.1)
				(type default)
			)
			(layer "F.Fab")
		)
		(fp_line
			(start 0.67945 -0.3048)
			(end 0.67945 0.3048)
			(stroke
				(width 0.1)
				(type default)
			)
			(layer "F.Fab")
		)
		(fp_line
			(start 0.67945 0.3048)
			(end 0.120396 0.3048)
			(stroke
				(width 0.1)
				(type default)
			)
			(layer "F.Fab")
		)
		(pad "1" smd circle
			(at -0.40005 0)
			(size 0 0)
			(layers "F.Cu" "F.Mask" "F.Paste")
			(net "GND")
		)
		(pad "2" smd circle
			(at 0.40005 0)
			(size 0 0)
			(layers "F.Cu" "F.Mask" "F.Paste")
			(net "GPU_BASE_FPGA_READY")
		)
	)
	(footprint ""
		(layer "F.Cu")
		(at 288.079942 -139.6492)
		(property "Reference" "R211"
			(at 0 0 0)
			(layer "F.SilkS")
			(hide yes)
			(effects
				(font
					(size 1.27 1.27)
				)
			)
		)
		(property "Value" ""
			(at 0 0 0)
			(layer "F.Fab")
			(effects
				(font
					(size 1.27 1.27)
				)
			)
		)
		(duplicate_pad_numbers_are_jumpers no)
		(fp_line
			(start -0.7874 -0.4064)
			(end 0.7874 -0.4064)
			(stroke
				(width 0.1524)
				(type default)
			)
			(layer "F.SilkS")
		)
		(fp_line
			(start -0.7874 0.4064)
			(end -0.7874 -0.4064)
			(stroke
				(width 0.1524)
				(type default)
			)
			(layer "F.SilkS")
		)
		(fp_line
			(start 0.7874 -0.4064)
			(end 0.7874 0.4064)
			(stroke
				(width 0.1524)
				(type default)
			)
			(layer "F.SilkS")
		)
		(fp_line
			(start 0.7874 0.4064)
			(end -0.7874 0.4064)
			(stroke
				(width 0.1524)
				(type default)
			)
			(layer "F.SilkS")
		)
		(fp_line
			(start -0.67945 -0.305054)
			(end -0.12065 -0.305054)
			(stroke
				(width 0.1)
				(type default)
			)
			(layer "F.Fab")
		)
		(fp_line
			(start -0.67945 0.3048)
			(end -0.67945 -0.305054)
			(stroke
				(width 0.1)
				(type default)
			)
			(layer "F.Fab")
		)
		(fp_line
			(start -0.12065 -0.305054)
			(end -0.12065 -0.2794)
			(stroke
				(width 0.1)
				(type default)
			)
			(layer "F.Fab")
		)
		(fp_line
			(start -0.12065 -0.2794)
			(end 0.12065 -0.2794)
			(stroke
				(width 0.1)
				(type default)
			)
			(layer "F.Fab")
		)
		(fp_line
			(start -0.12065 0.2794)
			(end -0.12065 0.3048)
			(stroke
				(width 0.1)
				(type default)
			)
			(layer "F.Fab")
		)
		(fp_line
			(start -0.12065 0.3048)
			(end -0.67945 0.3048)
			(stroke
				(width 0.1)
				(type default)
			)
			(layer "F.Fab")
		)
		(fp_line
			(start 0.120396 0.2794)
			(end -0.12065 0.2794)
			(stroke
				(width 0.1)
				(type default)
			)
			(layer "F.Fab")
		)
		(fp_line
			(start 0.120396 0.3048)
			(end 0.120396 0.2794)
			(stroke
				(width 0.1)
				(type default)
			)
			(layer "F.Fab")
		)
		(fp_line
			(start 0.12065 -0.3048)
			(end 0.67945 -0.3048)
			(stroke
				(width 0.1)
				(type default)
			)
			(layer "F.Fab")
		)
		(fp_line
			(start 0.12065 -0.2794)
			(end 0.12065 -0.3048)
			(stroke
				(width 0.1)
				(type default)
			)
			(layer "F.Fab")
		)
		(fp_line
			(start 0.67945 -0.3048)
			(end 0.67945 0.3048)
			(stroke
				(width 0.1)
				(type default)
			)
			(layer "F.Fab")
		)
		(fp_line
			(start 0.67945 0.3048)
			(end 0.120396 0.3048)
			(stroke
				(width 0.1)
				(type default)
			)
			(layer "F.Fab")
		)
		(pad "1" smd circle
			(at -0.40005 0)
			(size 0 0)
			(layers "F.Cu" "F.Mask" "F.Paste")
			(net "PRSNTB2_NIC4_N")
		)
		(pad "2" smd circle
			(at 0.40005 0)
			(size 0 0)
			(layers "F.Cu" "F.Mask" "F.Paste")
			(net "P3V3_AUX")
		)
	)
	(footprint ""
		(layer "F.Cu")
		(at 26.267918 -52.035456 180)
		(property "Reference" "R861"
			(at 0 0 180)
			(layer "F.SilkS")
			(hide yes)
			(effects
				(font
					(size 1.27 1.27)
				)
			)
		)
		(property "Value" ""
			(at 0 0 180)
			(layer "F.Fab")
			(effects
				(font
					(size 1.27 1.27)
				)
			)
		)
		(duplicate_pad_numbers_are_jumpers no)
		(fp_line
			(start 0.7874 0.4064)
			(end -0.7874 0.4064)
			(stroke
				(width 0.1524)
				(type default)
			)
			(layer "F.SilkS")
		)
		(fp_line
			(start 0.7874 -0.4064)
			(end 0.7874 0.4064)
			(stroke
				(width 0.1524)
				(type default)
			)
			(layer "F.SilkS")
		)
		(fp_line
			(start -0.7874 0.4064)
			(end -0.7874 -0.4064)
			(stroke
				(width 0.1524)
				(type default)
			)
			(layer "F.SilkS")
		)
		(fp_line
			(start -0.7874 -0.4064)
			(end 0.7874 -0.4064)
			(stroke
				(width 0.1524)
				(type default)
			)
			(layer "F.SilkS")
		)
		(fp_line
			(start 0.67945 0.3048)
			(end 0.120396 0.3048)
			(stroke
				(width 0.1)
				(type default)
			)
			(layer "F.Fab")
		)
		(fp_line
			(start 0.67945 -0.3048)
			(end 0.67945 0.3048)
			(stroke
				(width 0.1)
				(type default)
			)
			(layer "F.Fab")
		)
		(fp_line
			(start 0.12065 -0.2794)
			(end 0.12065 -0.3048)
			(stroke
				(width 0.1)
				(type default)
			)
			(layer "F.Fab")
		)
		(fp_line
			(start 0.12065 -0.3048)
			(end 0.67945 -0.3048)
			(stroke
				(width 0.1)
				(type default)
			)
			(layer "F.Fab")
		)
		(fp_line
			(start 0.120396 0.3048)
			(end 0.120396 0.2794)
			(stroke
				(width 0.1)
				(type default)
			)
			(layer "F.Fab")
		)
		(fp_line
			(start 0.120396 0.2794)
			(end -0.12065 0.2794)
			(stroke
				(width 0.1)
				(type default)
			)
			(layer "F.Fab")
		)
		(fp_line
			(start -0.12065 0.3048)
			(end -0.67945 0.3048)
			(stroke
				(width 0.1)
				(type default)
			)
			(layer "F.Fab")
		)
		(fp_line
			(start -0.12065 0.2794)
			(end -0.12065 0.3048)
			(stroke
				(width 0.1)
				(type default)
			)
			(layer "F.Fab")
		)
		(fp_line
			(start -0.12065 -0.2794)
			(end 0.12065 -0.2794)
			(stroke
				(width 0.1)
				(type default)
			)
			(layer "F.Fab")
		)
		(fp_line
			(start -0.12065 -0.305054)
			(end -0.12065 -0.2794)
			(stroke
				(width 0.1)
				(type default)
			)
			(layer "F.Fab")
		)
		(fp_line
			(start -0.67945 0.3048)
			(end -0.67945 -0.305054)
			(stroke
				(width 0.1)
				(type default)
			)
			(layer "F.Fab")
		)
		(fp_line
			(start -0.67945 -0.305054)
			(end -0.12065 -0.305054)
			(stroke
				(width 0.1)
				(type default)
			)
			(layer "F.Fab")
		)
		(pad "1" smd circle
			(at -0.40005 0 180)
			(size 0 0)
			(layers "F.Cu" "F.Mask" "F.Paste")
			(net "P3V3_AUX")
		)
		(pad "2" smd circle
			(at 0.40005 0 180)
			(size 0 0)
			(layers "F.Cu" "F.Mask" "F.Paste")
			(net "PWRGD_P12V_SSD0")
		)
	)
	(footprint ""
		(layer "F.Cu")
		(at 58.995056 -104.830372 180)
		(property "Reference" "R71"
			(at 0 0 180)
			(layer "F.SilkS")
			(hide yes)
			(effects
				(font
					(size 1.27 1.27)
				)
			)
		)
		(property "Value" ""
			(at 0 0 180)
			(layer "F.Fab")
			(effects
				(font
					(size 1.27 1.27)
				)
			)
		)
		(duplicate_pad_numbers_are_jumpers no)
		(fp_line
			(start 0.7874 0.4064)
			(end -0.7874 0.4064)
			(stroke
				(width 0.1524)
				(type default)
			)
			(layer "F.SilkS")
		)
		(fp_line
			(start 0.7874 -0.4064)
			(end 0.7874 0.4064)
			(stroke
				(width 0.1524)
				(type default)
			)
			(layer "F.SilkS")
		)
		(fp_line
			(start -0.7874 0.4064)
			(end -0.7874 -0.4064)
			(stroke
				(width 0.1524)
				(type default)
			)
			(layer "F.SilkS")
		)
		(fp_line
			(start -0.7874 -0.4064)
			(end 0.7874 -0.4064)
			(stroke
				(width 0.1524)
				(type default)
			)
			(layer "F.SilkS")
		)
		(fp_line
			(start 0.67945 0.3048)
			(end 0.120396 0.3048)
			(stroke
				(width 0.1)
				(type default)
			)
			(layer "F.Fab")
		)
		(fp_line
			(start 0.67945 -0.3048)
			(end 0.67945 0.3048)
			(stroke
				(width 0.1)
				(type default)
			)
			(layer "F.Fab")
		)
		(fp_line
			(start 0.12065 -0.2794)
			(end 0.12065 -0.3048)
			(stroke
				(width 0.1)
				(type default)
			)
			(layer "F.Fab")
		)
		(fp_line
			(start 0.12065 -0.3048)
			(end 0.67945 -0.3048)
			(stroke
				(width 0.1)
				(type default)
			)
			(layer "F.Fab")
		)
		(fp_line
			(start 0.120396 0.3048)
			(end 0.120396 0.2794)
			(stroke
				(width 0.1)
				(type default)
			)
			(layer "F.Fab")
		)
		(fp_line
			(start 0.120396 0.2794)
			(end -0.12065 0.2794)
			(stroke
				(width 0.1)
				(type default)
			)
			(layer "F.Fab")
		)
		(fp_line
			(start -0.12065 0.3048)
			(end -0.67945 0.3048)
			(stroke
				(width 0.1)
				(type default)
			)
			(layer "F.Fab")
		)
		(fp_line
			(start -0.12065 0.2794)
			(end -0.12065 0.3048)
			(stroke
				(width 0.1)
				(type default)
			)
			(layer "F.Fab")
		)
		(fp_line
			(start -0.12065 -0.2794)
			(end 0.12065 -0.2794)
			(stroke
				(width 0.1)
				(type default)
			)
			(layer "F.Fab")
		)
		(fp_line
			(start -0.12065 -0.305054)
			(end -0.12065 -0.2794)
			(stroke
				(width 0.1)
				(type default)
			)
			(layer "F.Fab")
		)
		(fp_line
			(start -0.67945 0.3048)
			(end -0.67945 -0.305054)
			(stroke
				(width 0.1)
				(type default)
			)
			(layer "F.Fab")
		)
		(fp_line
			(start -0.67945 -0.305054)
			(end -0.12065 -0.305054)
			(stroke
				(width 0.1)
				(type default)
			)
			(layer "F.Fab")
		)
		(pad "1" smd circle
			(at -0.40005 0 180)
			(size 0 0)
			(layers "F.Cu" "F.Mask" "F.Paste")
			(net "CLK_50M_NIC1_RBT_REF")
		)
		(pad "2" smd circle
			(at 0.40005 0 180)
			(size 0 0)
			(layers "F.Cu" "F.Mask" "F.Paste")
			(net "GND")
		)
	)
	(footprint ""
		(layer "F.Cu")
		(at 264.066782 -52.543456 180)
		(property "Reference" "PC560"
			(at 0 0 180)
			(layer "F.SilkS")
			(hide yes)
			(effects
				(font
					(size 1.27 1.27)
				)
			)
		)
		(property "Value" ""
			(at 0 0 180)
			(layer "F.Fab")
			(effects
				(font
					(size 1.27 1.27)
				)
			)
		)
		(duplicate_pad_numbers_are_jumpers no)
		(fp_line
			(start 0.7874 0.4064)
			(end -0.7874 0.4064)
			(stroke
				(width 0.1524)
				(type default)
			)
			(layer "F.SilkS")
		)
		(fp_line
			(start 0.7874 -0.4064)
			(end 0.7874 0.4064)
			(stroke
				(width 0.1524)
				(type default)
			)
			(layer "F.SilkS")
		)
		(fp_line
			(start -0.7874 0.4064)
			(end -0.7874 -0.4064)
			(stroke
				(width 0.1524)
				(type default)
			)
			(layer "F.SilkS")
		)
		(fp_line
			(start -0.7874 -0.4064)
			(end 0.7874 -0.4064)
			(stroke
				(width 0.1524)
				(type default)
			)
			(layer "F.SilkS")
		)
		(fp_line
			(start 0.67945 0.3048)
			(end 0.120396 0.3048)
			(stroke
				(width 0.1)
				(type default)
			)
			(layer "F.Fab")
		)
		(fp_line
			(start 0.67945 -0.3048)
			(end 0.67945 0.3048)
			(stroke
				(width 0.1)
				(type default)
			)
			(layer "F.Fab")
		)
		(fp_line
			(start 0.12065 -0.2794)
			(end 0.12065 -0.3048)
			(stroke
				(width 0.1)
				(type default)
			)
			(layer "F.Fab")
		)
		(fp_line
			(start 0.12065 -0.3048)
			(end 0.67945 -0.3048)
			(stroke
				(width 0.1)
				(type default)
			)
			(layer "F.Fab")
		)
		(fp_line
			(start 0.120396 0.3048)
			(end 0.120396 0.2794)
			(stroke
				(width 0.1)
				(type default)
			)
			(layer "F.Fab")
		)
		(fp_line
			(start 0.120396 0.2794)
			(end -0.12065 0.2794)
			(stroke
				(width 0.1)
				(type default)
			)
			(layer "F.Fab")
		)
		(fp_line
			(start -0.12065 0.3048)
			(end -0.67945 0.3048)
			(stroke
				(width 0.1)
				(type default)
			)
			(layer "F.Fab")
		)
		(fp_line
			(start -0.12065 0.2794)
			(end -0.12065 0.3048)
			(stroke
				(width 0.1)
				(type default)
			)
			(layer "F.Fab")
		)
		(fp_line
			(start -0.12065 -0.2794)
			(end 0.12065 -0.2794)
			(stroke
				(width 0.1)
				(type default)
			)
			(layer "F.Fab")
		)
		(fp_line
			(start -0.12065 -0.305054)
			(end -0.12065 -0.2794)
			(stroke
				(width 0.1)
				(type default)
			)
			(layer "F.Fab")
		)
		(fp_line
			(start -0.67945 0.3048)
			(end -0.67945 -0.305054)
			(stroke
				(width 0.1)
				(type default)
			)
			(layer "F.Fab")
		)
		(fp_line
			(start -0.67945 -0.305054)
			(end -0.12065 -0.305054)
			(stroke
				(width 0.1)
				(type default)
			)
			(layer "F.Fab")
		)
		(pad "1" smd circle
			(at -0.40005 0 180)
			(size 0 0)
			(layers "F.Cu" "F.Mask" "F.Paste")
			(net "P3V3_SSD9")
		)
		(pad "2" smd circle
			(at 0.40005 0 180)
			(size 0 0)
			(layers "F.Cu" "F.Mask" "F.Paste")
			(net "GND")
		)
	)
	(footprint ""
		(layer "F.Cu")
		(at 52.267866 -54.067456)
		(property "Reference" "PR213"
			(at 0 0 0)
			(layer "F.SilkS")
			(hide yes)
			(effects
				(font
					(size 1.27 1.27)
				)
			)
		)
		(property "Value" ""
			(at 0 0 0)
			(layer "F.Fab")
			(effects
				(font
					(size 1.27 1.27)
				)
			)
		)
		(duplicate_pad_numbers_are_jumpers no)
		(fp_line
			(start -0.7874 -0.4064)
			(end 0.7874 -0.4064)
			(stroke
				(width 0.1524)
				(type default)
			)
			(layer "F.SilkS")
		)
		(fp_line
			(start -0.7874 0.4064)
			(end -0.7874 -0.4064)
			(stroke
				(width 0.1524)
				(type default)
			)
			(layer "F.SilkS")
		)
		(fp_line
			(start 0.7874 -0.4064)
			(end 0.7874 0.4064)
			(stroke
				(width 0.1524)
				(type default)
			)
			(layer "F.SilkS")
		)
		(fp_line
			(start 0.7874 0.4064)
			(end -0.7874 0.4064)
			(stroke
				(width 0.1524)
				(type default)
			)
			(layer "F.SilkS")
		)
		(fp_line
			(start -0.67945 -0.305054)
			(end -0.12065 -0.305054)
			(stroke
				(width 0.1)
				(type default)
			)
			(layer "F.Fab")
		)
		(fp_line
			(start -0.67945 0.3048)
			(end -0.67945 -0.305054)
			(stroke
				(width 0.1)
				(type default)
			)
			(layer "F.Fab")
		)
		(fp_line
			(start -0.12065 -0.305054)
			(end -0.12065 -0.2794)
			(stroke
				(width 0.1)
				(type default)
			)
			(layer "F.Fab")
		)
		(fp_line
			(start -0.12065 -0.2794)
			(end 0.12065 -0.2794)
			(stroke
				(width 0.1)
				(type default)
			)
			(layer "F.Fab")
		)
		(fp_line
			(start -0.12065 0.2794)
			(end -0.12065 0.3048)
			(stroke
				(width 0.1)
				(type default)
			)
			(layer "F.Fab")
		)
		(fp_line
			(start -0.12065 0.3048)
			(end -0.67945 0.3048)
			(stroke
				(width 0.1)
				(type default)
			)
			(layer "F.Fab")
		)
		(fp_line
			(start 0.120396 0.2794)
			(end -0.12065 0.2794)
			(stroke
				(width 0.1)
				(type default)
			)
			(layer "F.Fab")
		)
		(fp_line
			(start 0.120396 0.3048)
			(end 0.120396 0.2794)
			(stroke
				(width 0.1)
				(type default)
			)
			(layer "F.Fab")
		)
		(fp_line
			(start 0.12065 -0.3048)
			(end 0.67945 -0.3048)
			(stroke
				(width 0.1)
				(type default)
			)
			(layer "F.Fab")
		)
		(fp_line
			(start 0.12065 -0.2794)
			(end 0.12065 -0.3048)
			(stroke
				(width 0.1)
				(type default)
			)
			(layer "F.Fab")
		)
		(fp_line
			(start 0.67945 -0.3048)
			(end 0.67945 0.3048)
			(stroke
				(width 0.1)
				(type default)
			)
			(layer "F.Fab")
		)
		(fp_line
			(start 0.67945 0.3048)
			(end 0.120396 0.3048)
			(stroke
				(width 0.1)
				(type default)
			)
			(layer "F.Fab")
		)
		(pad "1" smd circle
			(at -0.40005 0)
			(size 0 0)
			(layers "F.Cu" "F.Mask" "F.Paste")
			(net "P12V_SSD1_OCP")
		)
		(pad "2" smd circle
			(at 0.40005 0)
			(size 0 0)
			(layers "F.Cu" "F.Mask" "F.Paste")
			(net "GND")
		)
	)
)
